# T6G (Grand Teton) — schematic netlist excerpt (pin names and nets, part order shuffled) for the footprints in the layout excerpt that follows; sources: Cadence DE-HDL packaged netlist, KiCad conversion of 04192023_DAF0TMB3IC0_F0TG_MB_C_brd_V02_OCP.brd

J27  SCONN288_DDR506112002KQ  IO  pkg DDR288S_1-1VXC  page 105
  VIN_BULK0  = P12V_MEM_CPU1
  RFU0  = NC
  VIN_MGMT  = P3V3_AUX
  HSCL  = I3C_SPD_DDRH_CPU1_SCL
  HSDA  = I3C_SPD_DDRH_CPU1_SDA
  VSS0  = GND
  DQ0_A  = M_H_CPU1_SA_DQ<0>
  VSS1  = GND
  DQ1_A  = M_H_CPU1_SA_DQ<1>
  VSS2  = GND
  DQS0_A_T  = M_H_CPU1_SA_DQS_DP<0>
  DQS0_A_C  = M_H_CPU1_SA_DQS_DN<0>
  VSS3  = GND
  DQ4_A  = M_H_CPU1_SA_DQ<4>
  VSS4  = GND
  DQ5_A  = M_H_CPU1_SA_DQ<5>
  VSS5  = GND
  DQ8_A  = M_H_CPU1_SA_DQ<8>
  VSS6  = GND
  DQ9_A  = M_H_CPU1_SA_DQ<9>
  VSS7  = GND
  DQS1_A_T  = M_H_CPU1_SA_DQS_DP<1>
  DQS1_A_C  = M_H_CPU1_SA_DQS_DN<1>
  VSS8  = GND
  DQ12_A  = M_H_CPU1_SA_DQ<12>
  VSS9  = GND
  DQ13_A  = M_H_CPU1_SA_DQ<13>
  VSS10  = GND
  DQ16_A  = M_H_CPU1_SA_DQ<16>
  VSS11  = GND
  DQ17_A  = M_H_CPU1_SA_DQ<17>
  VSS12  = GND
  DQS2_A_T  = M_H_CPU1_SA_DQS_DP<2>
  DQS2_A_C  = M_H_CPU1_SA_DQS_DN<2>
  VSS13  = GND
  DQ20_A  = M_H_CPU1_SA_DQ<20>
  VSS14  = GND
  DQ21_A  = M_H_CPU1_SA_DQ<21>
  VSS15  = GND
  DQ24_A  = M_H_CPU1_SA_DQ<24>
  VSS16  = GND
  DQ25_A  = M_H_CPU1_SA_DQ<25>
  VSS17  = GND
  DQS3_A_T  = M_H_CPU1_SA_DQS_DP<3>
  DQS3_A_C  = M_H_CPU1_SA_DQS_DN<3>
  VSS18  = GND
  DQ28_A  = M_H_CPU1_SA_DQ<28>
  VSS19  = GND
  DQ29_A  = M_H_CPU1_SA_DQ<29>
  VSS20  = GND
  CB0_A  = M_H_CPU1_SA_CB<0>
  VSS21  = GND
  CB1_A  = M_H_CPU1_SA_CB<1>
  VSS22  = GND
  DQS4_A_T  = M_H_CPU1_SA_DQS_DP<4>
  DQS4_A_C  = M_H_CPU1_SA_DQS_DN<4>
  VSS23  = GND
  CB4_A  = M_H_CPU1_SA_CB<4>
  VSS24  = GND
  CB5_A  = M_H_CPU1_SA_CB<5>
  VSS25  = GND
  ALERT_N  = M_H_CPU1_ALERT_N
  VSS26  = GND
  CS0_A_N  = M_H_CPU1_SA_CS_N<0>
  VSS27  = GND
  CA0_A  = M_H_CPU1_SA_CA<0>
  VSS28  = GND
  CA2_A  = M_H_CPU1_SA_CA<2>
  VSS29  = GND
  CA4_A  = M_H_CPU1_SA_CA<4>
  VSS30  = GND
  CA6_A  = M_H_CPU1_SA_CA<6>
  VSS31  = GND
  PAR_A  = M_H_CPU1_SA_PAR
  VSS32  = GND
  CA0_B  = M_H_CPU1_SB_CA<0>
  VSS33  = GND
  CA2_B  = M_H_CPU1_SB_CA<2>
  VSS34  = GND
  CA4_B  = M_H_CPU1_SB_CA<4>
  VSS35  = GND
  CA6_B  = M_H_CPU1_SB_CA<6>
  VSS36  = GND
  CS0_B_N  = M_H_CPU1_SB_CS_N<0>
  VSS37  = GND
  \lbd||rsp_a_n\  = M_H_CPU1_SA_RSP<0>
  \lbs||rsp_b_n\  = M_H_CPU1_SB_RSP<0>
  VSS38  = GND
  CB4_B  = M_H_CPU1_SB_CB<4>
  VSS39  = GND
  CB5_B  = M_H_CPU1_SB_CB<5>
  VSS40  = GND
  \dqs9_b_t||tdqs9_b_t||dbi4_b_n\  = M_H_CPU1_SB_DQS_DP<9>
  \dqs9_b_c||tdqs9_b_c\  = M_H_CPU1_SB_DQS_DN<9>
  VSS41  = GND
  CB0_B  = M_H_CPU1_SB_CB<0>
  VSS42  = GND
  CB1_B  = M_H_CPU1_SB_CB<1>
  VSS43  = GND
  DQ0_B  = M_H_CPU1_SB_DQ<0>
  VSS44  = GND
  DQ1_B  = M_H_CPU1_SB_DQ<1>
  VSS45  = GND
  DQS0_B_T  = M_H_CPU1_SB_DQS_DP<0>
  DQS0_B_C  = M_H_CPU1_SB_DQS_DN<0>
  VSS46  = GND
  DQ4_B  = M_H_CPU1_SB_DQ<4>
  VSS47  = GND
  DQ5_B  = M_H_CPU1_SB_DQ<5>
  VSS48  = GND
  DQ8_B  = M_H_CPU1_SB_DQ<8>
  VSS49  = GND
  DQ9_B  = M_H_CPU1_SB_DQ<9>
  VSS50  = GND
  DQS1_B_T  = M_H_CPU1_SB_DQS_DP<1>
  DQS1_B_C  = M_H_CPU1_SB_DQS_DN<1>
  VSS51  = GND
  DQ12_B  = M_H_CPU1_SB_DQ<12>
  VSS52  = GND
  DQ13_B  = M_H_CPU1_SB_DQ<13>
  VSS53  = GND
  DQ16_B  = M_H_CPU1_SB_DQ<16>
  VSS54  = GND
  DQ17_B  = M_H_CPU1_SB_DQ<17>
  VSS55  = GND
  DQS2_B_T  = M_H_CPU1_SB_DQS_DP<2>
  DQS2_B_C  = M_H_CPU1_SB_DQS_DN<2>
  VSS56  = GND
  DQ20_B  = M_H_CPU1_SB_DQ<20>
  VSS57  = GND
  DQ21_B  = M_H_CPU1_SB_DQ<21>
  VSS58  = GND
  DQ24_B  = M_H_CPU1_SB_DQ<24>
  VSS59  = GND
  DQ25_B  = M_H_CPU1_SB_DQ<25>
  VSS60  = GND
  DQS3_B_T  = M_H_CPU1_SB_DQS_DP<3>
  DQS3_B_C  = M_H_CPU1_SB_DQS_DN<3>
  VSS61  = GND
  DQ28_B  = M_H_CPU1_SB_DQ<28>
  VSS62  = GND
  DQ29_B  = M_H_CPU1_SB_DQ<29>
  VSS63  = GND
  RFU1  = NC
  VIN_BULK1  = P12V_MEM_CPU1
  VIN_BULK2  = P12V_MEM_CPU1
  \pwr_good||fail_n\  = PWRGD_CHH_CPU1_DIMM
  HAS  = PD_CHH_CPU1_DIMM_SAA
  RFU2  = NC
  RFU3  = NC
  VSS64  = GND
  DQ2_A  = M_H_CPU1_SA_DQ<2>
  VSS65  = GND
  DQ3_A  = M_H_CPU1_SA_DQ<3>
  VSS66  = GND
  \dqs5_a_c||tdqs5_a_c||dqs5_a_t||tdqs5_a_t\  = M_H_CPU1_SA_DQS_DN<5>
  \dqs5_a_t||tdqs5_a_t\  = M_H_CPU1_SA_DQS_DP<5>
  VSS67  = GND
  DQ6_A  = M_H_CPU1_SA_DQ<6>
  VSS68  = GND
  DQ7_A  = M_H_CPU1_SA_DQ<7>
  VSS69  = GND
  DQ10_A  = M_H_CPU1_SA_DQ<10>
  VSS70  = GND
  DQ11_A  = M_H_CPU1_SA_DQ<11>
  VSS71  = GND
  \dqs6_a_c||tdqs6_a_c||dqs6_a_t||tdqs6_a_t\  = M_H_CPU1_SA_DQS_DN<6>
  \dqs6_a_t||tdqs6_a_t\  = M_H_CPU1_SA_DQS_DP<6>
  VSS72  = GND
  DQ14_A  = M_H_CPU1_SA_DQ<14>
  VSS73  = GND
  DQ15_A  = M_H_CPU1_SA_DQ<15>
  VSS74  = GND
  DQ18_A  = M_H_CPU1_SA_DQ<18>
  VSS75  = GND
  DQ19_A  = M_H_CPU1_SA_DQ<19>
  VSS76  = GND
  \dqs7_a_c||tdqs7_a_c\  = M_H_CPU1_SA_DQS_DN<7>
  \dqs7_a_t||tdqs7_a_t\  = M_H_CPU1_SA_DQS_DP<7>
  VSS77  = GND
  DQ22_A  = M_H_CPU1_SA_DQ<22>
  VSS78  = GND
  DQ23_A  = M_H_CPU1_SA_DQ<23>
  VSS79  = GND
  DQ26_A  = M_H_CPU1_SA_DQ<26>
  VSS80  = GND
  DQ27_A  = M_H_CPU1_SA_DQ<27>
  VSS81  = GND
  \dqs8_a_c||tdqs8_a_c\  = M_H_CPU1_SA_DQS_DN<8>
  \dqs8_a_t||tdqs8_a_t\  = M_H_CPU1_SA_DQS_DP<8>
  VSS82  = GND
  DQ30_A  = M_H_CPU1_SA_DQ<30>
  VSS83  = GND
  DQ31_A  = M_H_CPU1_SA_DQ<31>
  VSS84  = GND
  CB2_A  = M_H_CPU1_SA_CB<2>
  VSS85  = GND
  CB3_A  = M_H_CPU1_SA_CB<3>
  VSS86  = GND
  \dqs9_a_c||tdqs9_a_c\  = M_H_CPU1_SA_DQS_DN<9>
  \dqs9_a_t||tdqs9_a_t\  = M_H_CPU1_SA_DQS_DP<9>
  VSS87  = GND
  CB6_A  = M_H_CPU1_SA_CB<6>
  VSS88  = GND
  CB7_A  = M_H_CPU1_SA_CB<7>
  VSS89  = GND
  RESET_N  = M_H_CPU1_RESET_N
  VSS90  = GND
  CS1_A_N  = M_H_CPU1_SA_CS_N<1>
  VSS91  = GND
  CA1_A  = M_H_CPU1_SA_CA<1>
  VSS92  = GND
  CA3_A  = M_H_CPU1_SA_CA<3>
  VSS93  = GND
  CA5_A  = M_H_CPU1_SA_CA<5>
  VSS94  = GND
  CK_T  = M_H_CPU1_CLK_DP<0>
  CK_C  = M_H_CPU1_CLK_DN<0>
  VSS95  = GND
  RFU4  = NC
  CA1_B  = M_H_CPU1_SB_CA<1>
  VSS96  = GND
  CA3_B  = M_H_CPU1_SB_CA<3>
  VSS97  = GND
  CA5_B  = M_H_CPU1_SB_CA<5>
  VSS98  = GND
  PAR_B  = M_H_CPU1_SB_PAR
  VSS99  = GND
  CS1_B_N  = M_H_CPU1_SB_CS_N<1>
  VSS100  = GND
  RFU5  = NC
  RFU6  = NC
  VSS101  = GND
  CB6_B  = M_H_CPU1_SB_CB<6>
  VSS102  = GND
  CB7_B  = M_H_CPU1_SB_CB<7>
  VSS103  = GND
  DQS4_B_C  = M_H_CPU1_SB_DQS_DN<4>
  DQS4_B_T  = M_H_CPU1_SB_DQS_DP<4>
  VSS104  = GND
  CB2_B  = M_H_CPU1_SB_CB<2>
  VSS105  = GND
  CB3_B  = M_H_CPU1_SB_CB<3>
  VSS106  = GND
  DQ2_B  = M_H_CPU1_SB_DQ<2>
  VSS107  = GND
  DQ3_B  = M_H_CPU1_SB_DQ<3>
  VSS108  = GND
  \dqs5_b_c||tdqs5_b_c\  = M_H_CPU1_SB_DQS_DN<5>
  \dqs5_b_t||tdqs5_b_t\  = M_H_CPU1_SB_DQS_DP<5>
  VSS109  = GND
  DQ6_B  = M_H_CPU1_SB_DQ<6>
  VSS110  = GND
  DQ7_B  = M_H_CPU1_SB_DQ<7>
  VSS111  = GND
  DQ10_B  = M_H_CPU1_SB_DQ<10>
  VSS112  = GND
  DQ11_B  = M_H_CPU1_SB_DQ<11>
  VSS113  = GND
  \dqs6_b_c||tdqs6_b_c\  = M_H_CPU1_SB_DQS_DN<6>
  \dqs6_b_t||tdqs6_b_t\  = M_H_CPU1_SB_DQS_DP<6>
  VSS114  = GND
  DQ14_B  = M_H_CPU1_SB_DQ<14>
  VSS115  = GND
  DQ15_B  = M_H_CPU1_SB_DQ<15>
  VSS116  = GND
  DQ18_B  = M_H_CPU1_SB_DQ<18>
  VSS117  = GND
  DQ19_B  = M_H_CPU1_SB_DQ<19>
  VSS118  = GND
  \dqs7_b_c||tdqs7_b_c\  = M_H_CPU1_SB_DQS_DN<7>
  \dqs7_b_t||tdqs7_b_t\  = M_H_CPU1_SB_DQS_DP<7>
  VSS119  = GND
  DQ22_B  = M_H_CPU1_SB_DQ<22>
  VSS120  = GND
  DQ23_B  = M_H_CPU1_SB_DQ<23>
  VSS121  = GND
  DQ26_B  = M_H_CPU1_SB_DQ<26>
  VSS122  = GND
  DQ27_B  = M_H_CPU1_SB_DQ<27>
  VSS123  = GND
  \dqs8_b_c||tdqs8_b_c\  = M_H_CPU1_SB_DQS_DN<8>
  \dqs8_b_t||tdqs8_b_t\  = M_H_CPU1_SB_DQS_DP<8>
  VSS124  = GND
  DQ30_B  = M_H_CPU1_SB_DQ<30>
  VSS125  = GND
  DQ31_B  = M_H_CPU1_SB_DQ<31>
  VSS126  = GND
  G1  = GND
  G2  = GND
  G3  = GND

(kicad_pcb
	(version 20260206)
	(generator "pcbnew")
	(generator_version "10.0")
	(general
		(thickness 1.6)
		(legacy_teardrops no)
	)
	(paper "A4")
	(title_block
		(title "04192023_DAF0TMB3IC0_F0TG_MB_C_brd_V02_OCP.brd")
		(comment 1 "Grand Teton / footprint 583 of 8354 (J27), pads 139-184 of 291")
	)
	(layers
		(0 "F.Cu" signal "TOP")
		(4 "In1.Cu" signal "GND")
		(6 "In2.Cu" signal "IN1")
		(8 "In3.Cu" signal "GND1")
		(10 "In4.Cu" signal "IN2")
		(12 "In5.Cu" signal "GND2")
		(14 "In6.Cu" signal "IN3")
		(16 "In7.Cu" signal "GND3")
		(18 "In8.Cu" signal "VCC")
		(20 "In9.Cu" signal "VCC1")
		(22 "In10.Cu" signal "GND4")
		(24 "In11.Cu" signal "IN4")
		(26 "In12.Cu" signal "GND5")
		(28 "In13.Cu" signal "IN5")
		(30 "In14.Cu" signal "GND6")
		(32 "In15.Cu" signal "IN6")
		(34 "In16.Cu" signal "GND7")
		(2 "B.Cu" signal "BOTTOM")
		(9 "F.Adhes" user "F.Adhesive")
		(11 "B.Adhes" user "B.Adhesive")
		(13 "F.Paste" user "Package Geometry/Pastemask Top")
		(15 "B.Paste" user "Package Geometry/Pastemask Bottom")
		(5 "F.SilkS" user "Ref Des/Silkscreen Top")
		(7 "B.SilkS" user "Ref Des/Silkscreen Bottom")
		(1 "F.Mask" user "Board Geometry/Soldermask Top")
		(3 "B.Mask" user "Board Geometry/Soldermask Bottom")
		(17 "Dwgs.User" user "User.Drawings")
		(19 "Cmts.User" user "User.Comments")
		(21 "Eco1.User" user "User.Eco1")
		(23 "Eco2.User" user "User.Eco2")
		(25 "Edge.Cuts" user "Board Geometry/Outline")
		(27 "Margin" user)
		(31 "F.CrtYd" user "Package Geometry/Place Bound Top")
		(29 "B.CrtYd" user "Package Geometry/Place Bound Bottom")
		(35 "F.Fab" user "Ref Des/Assembly Top")
		(33 "B.Fab" user "Ref Des/Assembly Bottom")
	)
	(footprint ""
		(layer "F.Cu")
		(at 174.022004 -255.560322 180)
		(property "Reference" "J27"
			(at -2.7178 -81.857088 0)
			(unlocked yes)
			(layer "F.SilkS")
			(effects
				(font
					(size 0.7874 0.5842)
					(thickness 0.1524)
				)
			)
		)
		(property "Value" ""
			(at 0 0 180)
			(layer "F.Fab")
			(effects
				(font
					(size 1.27 1.27)
				)
			)
		)
		(duplicate_pad_numbers_are_jumpers no)
		(pad "139" smd rect
			(at -2.050034 59.075066 90)
			(size 0.519938 1.4986)
			(layers "F.Cu" "F.Mask" "F.Paste")
			(net "GND")
		)
		(pad "140" smd rect
			(at -2.050034 59.92495 90)
			(size 0.519938 1.4986)
			(layers "F.Cu" "F.Mask" "F.Paste")
			(net "M_H_CPU1_SB_DQ<28>")
		)
		(pad "141" smd rect
			(at -2.050034 60.775088 90)
			(size 0.519938 1.4986)
			(layers "F.Cu" "F.Mask" "F.Paste")
			(net "GND")
		)
		(pad "142" smd rect
			(at -2.050034 61.624972 90)
			(size 0.519938 1.4986)
			(layers "F.Cu" "F.Mask" "F.Paste")
			(net "M_H_CPU1_SB_DQ<29>")
		)
		(pad "143" smd rect
			(at -2.050034 62.47511 90)
			(size 0.519938 1.4986)
			(layers "F.Cu" "F.Mask" "F.Paste")
			(net "GND")
		)
		(pad "144" smd rect
			(at -2.050034 63.324994 90)
			(size 0.519938 1.4986)
			(layers "F.Cu" "F.Mask" "F.Paste")
			(net "Net_2355")
		)
		(pad "145" smd rect
			(at 2.050034 -63.324994 90)
			(size 0.519938 1.4986)
			(layers "F.Cu" "F.Mask" "F.Paste")
			(net "P12V_MEM_CPU1")
		)
		(pad "146" smd rect
			(at 2.050034 -62.47511 90)
			(size 0.519938 1.4986)
			(layers "F.Cu" "F.Mask" "F.Paste")
			(net "P12V_MEM_CPU1")
		)
		(pad "147" smd rect
			(at 2.050034 -61.624972 90)
			(size 0.519938 1.4986)
			(layers "F.Cu" "F.Mask" "F.Paste")
			(net "PWRGD_CHH_CPU1_DIMM")
		)
		(pad "148" smd rect
			(at 2.050034 -60.775088 90)
			(size 0.519938 1.4986)
			(layers "F.Cu" "F.Mask" "F.Paste")
			(net "PD_CHH_CPU1_DIMM_SAA")
		)
		(pad "149" smd rect
			(at 2.050034 -59.92495 90)
			(size 0.519938 1.4986)
			(layers "F.Cu" "F.Mask" "F.Paste")
			(net "Net_2356")
		)
		(pad "150" smd rect
			(at 2.050034 -59.075066 90)
			(size 0.519938 1.4986)
			(layers "F.Cu" "F.Mask" "F.Paste")
			(net "Net_2357")
		)
		(pad "151" smd rect
			(at 2.050034 -58.224928 90)
			(size 0.519938 1.4986)
			(layers "F.Cu" "F.Mask" "F.Paste")
			(net "GND")
		)
		(pad "152" smd rect
			(at 2.050034 -57.375044 90)
			(size 0.519938 1.4986)
			(layers "F.Cu" "F.Mask" "F.Paste")
			(net "M_H_CPU1_SA_DQ<2>")
		)
		(pad "153" smd rect
			(at 2.050034 -56.524906 90)
			(size 0.519938 1.4986)
			(layers "F.Cu" "F.Mask" "F.Paste")
			(net "GND")
		)
		(pad "154" smd rect
			(at 2.050034 -55.675022 90)
			(size 0.519938 1.4986)
			(layers "F.Cu" "F.Mask" "F.Paste")
			(net "M_H_CPU1_SA_DQ<3>")
		)
		(pad "155" smd rect
			(at 2.050034 -54.824884 90)
			(size 0.519938 1.4986)
			(layers "F.Cu" "F.Mask" "F.Paste")
			(net "GND")
		)
		(pad "156" smd rect
			(at 2.050034 -53.975 90)
			(size 0.519938 1.4986)
			(layers "F.Cu" "F.Mask" "F.Paste")
			(net "M_H_CPU1_SA_DQS_DN<5>")
		)
		(pad "157" smd rect
			(at 2.050034 -53.125116 90)
			(size 0.519938 1.4986)
			(layers "F.Cu" "F.Mask" "F.Paste")
			(net "M_H_CPU1_SA_DQS_DP<5>")
		)
		(pad "158" smd rect
			(at 2.050034 -52.274978 90)
			(size 0.519938 1.4986)
			(layers "F.Cu" "F.Mask" "F.Paste")
			(net "GND")
		)
		(pad "159" smd rect
			(at 2.050034 -51.425094 90)
			(size 0.519938 1.4986)
			(layers "F.Cu" "F.Mask" "F.Paste")
			(net "M_H_CPU1_SA_DQ<6>")
		)
		(pad "160" smd rect
			(at 2.050034 -50.574956 90)
			(size 0.519938 1.4986)
			(layers "F.Cu" "F.Mask" "F.Paste")
			(net "GND")
		)
		(pad "161" smd rect
			(at 2.050034 -49.725072 90)
			(size 0.519938 1.4986)
			(layers "F.Cu" "F.Mask" "F.Paste")
			(net "M_H_CPU1_SA_DQ<7>")
		)
		(pad "162" smd rect
			(at 2.050034 -48.874934 90)
			(size 0.519938 1.4986)
			(layers "F.Cu" "F.Mask" "F.Paste")
			(net "GND")
		)
		(pad "163" smd rect
			(at 2.050034 -48.02505 90)
			(size 0.519938 1.4986)
			(layers "F.Cu" "F.Mask" "F.Paste")
			(net "M_H_CPU1_SA_DQ<10>")
		)
		(pad "164" smd rect
			(at 2.050034 -47.174912 90)
			(size 0.519938 1.4986)
			(layers "F.Cu" "F.Mask" "F.Paste")
			(net "GND")
		)
		(pad "165" smd rect
			(at 2.050034 -46.325028 90)
			(size 0.519938 1.4986)
			(layers "F.Cu" "F.Mask" "F.Paste")
			(net "M_H_CPU1_SA_DQ<11>")
		)
		(pad "166" smd rect
			(at 2.050034 -45.47489 90)
			(size 0.519938 1.4986)
			(layers "F.Cu" "F.Mask" "F.Paste")
			(net "GND")
		)
		(pad "167" smd rect
			(at 2.050034 -44.625006 90)
			(size 0.519938 1.4986)
			(layers "F.Cu" "F.Mask" "F.Paste")
			(net "M_H_CPU1_SA_DQS_DN<6>")
		)
		(pad "168" smd rect
			(at 2.050034 -43.775122 90)
			(size 0.519938 1.4986)
			(layers "F.Cu" "F.Mask" "F.Paste")
			(net "M_H_CPU1_SA_DQS_DP<6>")
		)
		(pad "169" smd rect
			(at 2.050034 -42.924984 90)
			(size 0.519938 1.4986)
			(layers "F.Cu" "F.Mask" "F.Paste")
			(net "GND")
		)
		(pad "170" smd rect
			(at 2.050034 -42.0751 90)
			(size 0.519938 1.4986)
			(layers "F.Cu" "F.Mask" "F.Paste")
			(net "M_H_CPU1_SA_DQ<14>")
		)
		(pad "171" smd rect
			(at 2.050034 -41.224962 90)
			(size 0.519938 1.4986)
			(layers "F.Cu" "F.Mask" "F.Paste")
			(net "GND")
		)
		(pad "172" smd rect
			(at 2.050034 -40.375078 90)
			(size 0.519938 1.4986)
			(layers "F.Cu" "F.Mask" "F.Paste")
			(net "M_H_CPU1_SA_DQ<15>")
		)
		(pad "173" smd rect
			(at 2.050034 -39.52494 90)
			(size 0.519938 1.4986)
			(layers "F.Cu" "F.Mask" "F.Paste")
			(net "GND")
		)
		(pad "174" smd rect
			(at 2.050034 -38.675056 90)
			(size 0.519938 1.4986)
			(layers "F.Cu" "F.Mask" "F.Paste")
			(net "M_H_CPU1_SA_DQ<18>")
		)
		(pad "175" smd rect
			(at 2.050034 -37.824918 90)
			(size 0.519938 1.4986)
			(layers "F.Cu" "F.Mask" "F.Paste")
			(net "GND")
		)
		(pad "176" smd rect
			(at 2.050034 -36.975034 90)
			(size 0.519938 1.4986)
			(layers "F.Cu" "F.Mask" "F.Paste")
			(net "M_H_CPU1_SA_DQ<19>")
		)
		(pad "177" smd rect
			(at 2.050034 -36.124896 90)
			(size 0.519938 1.4986)
			(layers "F.Cu" "F.Mask" "F.Paste")
			(net "GND")
		)
		(pad "178" smd rect
			(at 2.050034 -35.275012 90)
			(size 0.519938 1.4986)
			(layers "F.Cu" "F.Mask" "F.Paste")
			(net "M_H_CPU1_SA_DQS_DN<7>")
		)
		(pad "179" smd rect
			(at 2.050034 -34.425128 90)
			(size 0.519938 1.4986)
			(layers "F.Cu" "F.Mask" "F.Paste")
			(net "M_H_CPU1_SA_DQS_DP<7>")
		)
		(pad "180" smd rect
			(at 2.050034 -33.57499 90)
			(size 0.519938 1.4986)
			(layers "F.Cu" "F.Mask" "F.Paste")
			(net "GND")
		)
		(pad "181" smd rect
			(at 2.050034 -32.725106 90)
			(size 0.519938 1.4986)
			(layers "F.Cu" "F.Mask" "F.Paste")
			(net "M_H_CPU1_SA_DQ<22>")
		)
		(pad "182" smd rect
			(at 2.050034 -31.874968 90)
			(size 0.519938 1.4986)
			(layers "F.Cu" "F.Mask" "F.Paste")
			(net "GND")
		)
		(pad "183" smd rect
			(at 2.050034 -31.025084 90)
			(size 0.519938 1.4986)
			(layers "F.Cu" "F.Mask" "F.Paste")
			(net "M_H_CPU1_SA_DQ<23>")
		)
		(pad "184" smd rect
			(at 2.050034 -30.174946 90)
			(size 0.519938 1.4986)
			(layers "F.Cu" "F.Mask" "F.Paste")
			(net "GND")
		)
	)
)
